# T6G (Grand Teton) — schematic netlist excerpt (pin names and nets, part order shuffled) for the footprints in the layout excerpt that follows; sources: Cadence DE-HDL packaged netlist, KiCad conversion of 04192023_DAF0TMB3IC0_F0TG_MB_C_brd_V02_OCP.brd

R1257  Q_RES  0 5% CHIP  pkg 0402LF  page 258 : A = P1V8_CPU1_RT_1D_ADC ; B = P1V8_CPU1_RT_1D_ADC_TIC
PC575_5  Q_CAP  22UF 4V 20% X6S  pkg C0805  page 196 : A = PVDDCR_CPU0_P0 ; B = GND
C6685  Q_CAP_DIFFBUS  DIFF BUS_0.22UF 6.3V 20% X6S  pkg C0201  page 330 : \1\ = P5E_CPU1_P1_TX_BUF_C_DP<12> ; \2\ = P5E_CPU1_P1_TX_BUF_DP<12>

(kicad_pcb
	(version 20260206)
	(generator "pcbnew")
	(generator_version "10.0")
	(general
		(thickness 1.6)
		(legacy_teardrops no)
	)
	(paper "A4")
	(title_block
		(title "04192023_DAF0TMB3IC0_F0TG_MB_C_brd_V02_OCP.brd")
		(comment 1 "Grand Teton / footprints 6868-6870 of 8354")
	)
	(layers
		(0 "F.Cu" signal "TOP")
		(4 "In1.Cu" signal "GND")
		(6 "In2.Cu" signal "IN1")
		(8 "In3.Cu" signal "GND1")
		(10 "In4.Cu" signal "IN2")
		(12 "In5.Cu" signal "GND2")
		(14 "In6.Cu" signal "IN3")
		(16 "In7.Cu" signal "GND3")
		(18 "In8.Cu" signal "VCC")
		(20 "In9.Cu" signal "VCC1")
		(22 "In10.Cu" signal "GND4")
		(24 "In11.Cu" signal "IN4")
		(26 "In12.Cu" signal "GND5")
		(28 "In13.Cu" signal "IN5")
		(30 "In14.Cu" signal "GND6")
		(32 "In15.Cu" signal "IN6")
		(34 "In16.Cu" signal "GND7")
		(2 "B.Cu" signal "BOTTOM")
		(9 "F.Adhes" user "F.Adhesive")
		(11 "B.Adhes" user "B.Adhesive")
		(13 "F.Paste" user "Package Geometry/Pastemask Top")
		(15 "B.Paste" user "Package Geometry/Pastemask Bottom")
		(5 "F.SilkS" user "Ref Des/Silkscreen Top")
		(7 "B.SilkS" user "Ref Des/Silkscreen Bottom")
		(1 "F.Mask" user "Board Geometry/Soldermask Top")
		(3 "B.Mask" user "Board Geometry/Soldermask Bottom")
		(17 "Dwgs.User" user "User.Drawings")
		(19 "Cmts.User" user "User.Comments")
		(21 "Eco1.User" user "User.Eco1")
		(23 "Eco2.User" user "User.Eco2")
		(25 "Edge.Cuts" user "Board Geometry/Outline")
		(27 "Margin" user)
		(31 "F.CrtYd" user "Package Geometry/Place Bound Top")
		(29 "B.CrtYd" user "Package Geometry/Place Bound Bottom")
		(35 "F.Fab" user "Ref Des/Assembly Top")
		(33 "B.Fab" user "Ref Des/Assembly Bottom")
	)
	(footprint ""
		(layer "B.Cu")
		(at 86.973664 -408.517344 90)
		(property "Reference" "C6685"
			(at 0 0 90)
			(layer "B.SilkS")
			(hide yes)
			(effects
				(font
					(size 1.27 1.27)
				)
				(justify mirror)
			)
		)
		(property "Value" ""
			(at 0 0 90)
			(layer "B.Fab")
			(effects
				(font
					(size 1.27 1.27)
				)
				(justify mirror)
			)
		)
		(duplicate_pad_numbers_are_jumpers no)
		(fp_line
			(start 0.299974 -0.150114)
			(end -0.299974 -0.150114)
			(stroke
				(width 0.1)
				(type default)
			)
			(layer "B.Fab")
		)
		(fp_line
			(start -0.299974 -0.150114)
			(end -0.299974 0.150114)
			(stroke
				(width 0.1)
				(type default)
			)
			(layer "B.Fab")
		)
		(fp_line
			(start 0.299974 0.150114)
			(end 0.299974 -0.150114)
			(stroke
				(width 0.1)
				(type default)
			)
			(layer "B.Fab")
		)
		(fp_line
			(start -0.299974 0.150114)
			(end 0.299974 0.150114)
			(stroke
				(width 0.1)
				(type default)
			)
			(layer "B.Fab")
		)
		(pad "1" smd rect
			(at 0.2667 0 270)
			(size 0.3048 0.381)
			(layers "B.Cu" "B.Mask" "B.Paste")
			(net "P5E_CPU1_P1_TX_BUF_C_DP<12>")
		)
		(pad "2" smd rect
			(at -0.2667 0 270)
			(size 0.3048 0.381)
			(layers "B.Cu" "B.Mask" "B.Paste")
			(net "P5E_CPU1_P1_TX_BUF_DP<12>")
		)
	)
	(footprint ""
		(layer "B.Cu")
		(at 231.072436 -326.07885)
		(property "Reference" "R1257"
			(at 0 0 0)
			(layer "B.SilkS")
			(hide yes)
			(effects
				(font
					(size 1.27 1.27)
				)
				(justify mirror)
			)
		)
		(property "Value" ""
			(at 0 0 0)
			(layer "B.Fab")
			(effects
				(font
					(size 1.27 1.27)
				)
				(justify mirror)
			)
		)
		(duplicate_pad_numbers_are_jumpers no)
		(fp_line
			(start -0.7874 -0.4064)
			(end -0.7874 0.4064)
			(stroke
				(width 0.1524)
				(type default)
			)
			(layer "B.SilkS")
		)
		(fp_line
			(start -0.7874 0.4064)
			(end 0.7874 0.4064)
			(stroke
				(width 0.1524)
				(type default)
			)
			(layer "B.SilkS")
		)
		(fp_line
			(start 0.7874 -0.4064)
			(end -0.7874 -0.4064)
			(stroke
				(width 0.1524)
				(type default)
			)
			(layer "B.SilkS")
		)
		(fp_line
			(start 0.7874 0.4064)
			(end 0.7874 -0.4064)
			(stroke
				(width 0.1524)
				(type default)
			)
			(layer "B.SilkS")
		)
		(fp_line
			(start -0.67945 -0.3048)
			(end -0.67945 0.3048)
			(stroke
				(width 0.1)
				(type default)
			)
			(layer "B.Fab")
		)
		(fp_line
			(start -0.67945 0.3048)
			(end -0.120396 0.3048)
			(stroke
				(width 0.1)
				(type default)
			)
			(layer "B.Fab")
		)
		(fp_line
			(start -0.12065 -0.3048)
			(end -0.67945 -0.3048)
			(stroke
				(width 0.1)
				(type default)
			)
			(layer "B.Fab")
		)
		(fp_line
			(start -0.12065 -0.2794)
			(end -0.12065 -0.3048)
			(stroke
				(width 0.1)
				(type default)
			)
			(layer "B.Fab")
		)
		(fp_line
			(start -0.120396 0.2794)
			(end 0.12065 0.2794)
			(stroke
				(width 0.1)
				(type default)
			)
			(layer "B.Fab")
		)
		(fp_line
			(start -0.120396 0.3048)
			(end -0.120396 0.2794)
			(stroke
				(width 0.1)
				(type default)
			)
			(layer "B.Fab")
		)
		(fp_line
			(start 0.12065 -0.305054)
			(end 0.12065 -0.2794)
			(stroke
				(width 0.1)
				(type default)
			)
			(layer "B.Fab")
		)
		(fp_line
			(start 0.12065 -0.2794)
			(end -0.12065 -0.2794)
			(stroke
				(width 0.1)
				(type default)
			)
			(layer "B.Fab")
		)
		(fp_line
			(start 0.12065 0.2794)
			(end 0.12065 0.3048)
			(stroke
				(width 0.1)
				(type default)
			)
			(layer "B.Fab")
		)
		(fp_line
			(start 0.12065 0.3048)
			(end 0.67945 0.3048)
			(stroke
				(width 0.1)
				(type default)
			)
			(layer "B.Fab")
		)
		(fp_line
			(start 0.67945 -0.305054)
			(end 0.12065 -0.305054)
			(stroke
				(width 0.1)
				(type default)
			)
			(layer "B.Fab")
		)
		(fp_line
			(start 0.67945 0.3048)
			(end 0.67945 -0.305054)
			(stroke
				(width 0.1)
				(type default)
			)
			(layer "B.Fab")
		)
		(pad "1" smd rect
			(at 0.40005 0)
			(size 0.4572 0.508)
			(layers "B.Cu" "B.Mask" "B.Paste")
			(net "P1V8_CPU1_RT_1D_ADC")
		)
		(pad "2" smd rect
			(at -0.40005 0)
			(size 0.4572 0.508)
			(layers "B.Cu" "B.Mask" "B.Paste")
			(net "P1V8_CPU1_RT_1D_ADC_TIC")
		)
	)
	(footprint ""
		(layer "B.Cu")
		(at 359.421176 -179.67452 90)
		(property "Reference" "PC575_5"
			(at 0 0 90)
			(layer "B.SilkS")
			(hide yes)
			(effects
				(font
					(size 1.27 1.27)
				)
				(justify mirror)
			)
		)
		(property "Value" ""
			(at 0 0 90)
			(layer "B.Fab")
			(effects
				(font
					(size 1.27 1.27)
				)
				(justify mirror)
			)
		)
		(duplicate_pad_numbers_are_jumpers no)
		(fp_line
			(start 1.524 -0.762)
			(end -1.524 -0.762)
			(stroke
				(width 0.1524)
				(type default)
			)
			(layer "B.SilkS")
		)
		(fp_line
			(start -1.524 -0.762)
			(end -1.524 0.762)
			(stroke
				(width 0.1524)
				(type default)
			)
			(layer "B.SilkS")
		)
		(fp_line
			(start 1.524 0.762)
			(end 1.524 -0.762)
			(stroke
				(width 0.1524)
				(type default)
			)
			(layer "B.SilkS")
		)
		(fp_line
			(start -1.524 0.762)
			(end 1.524 0.762)
			(stroke
				(width 0.1524)
				(type default)
			)
			(layer "B.SilkS")
		)
		(fp_line
			(start 1.1049 -0.724916)
			(end 1.1049 0.724916)
			(stroke
				(width 0.1)
				(type default)
			)
			(layer "B.Fab")
		)
		(fp_line
			(start -1.1049 -0.724916)
			(end 1.1049 -0.724916)
			(stroke
				(width 0.1)
				(type default)
			)
			(layer "B.Fab")
		)
		(fp_line
			(start 1.1049 0.724916)
			(end -1.1049 0.724916)
			(stroke
				(width 0.1)
				(type default)
			)
			(layer "B.Fab")
		)
		(fp_line
			(start -1.1049 0.724916)
			(end -1.1049 -0.724916)
			(stroke
				(width 0.1)
				(type default)
			)
			(layer "B.Fab")
		)
		(pad "1" smd rect
			(at 0.889 0 90)
			(size 1.016 1.27)
			(layers "B.Cu" "B.Mask" "B.Paste")
			(net "PVDDCR_CPU0_P0")
		)
		(pad "2" smd rect
			(at -0.889 0 90)
			(size 1.016 1.27)
			(layers "B.Cu" "B.Mask" "B.Paste")
			(net "GND")
		)
	)
)
